(kicad_pcb
	(version 20260206)
	(generator "pcbnew")
	(generator_version "10.0")
	(general
		(thickness 1.6)
		(legacy_teardrops no)
	)
	(paper "A4")
	(title_block
		(title "03242023_DA0F0TMBIJ0_F0T_Motherboard_J_brd_V01_OCP.brd")
		(comment 1 "Grand Teton / footprints 3581-3585 of 6105")
	)
	(layers
		(0 "F.Cu" signal "TOP")
		(4 "In1.Cu" signal "GND")
		(6 "In2.Cu" signal "IN1")
		(8 "In3.Cu" signal "GND1")
		(10 "In4.Cu" signal "IN2")
		(12 "In5.Cu" signal "GND2")
		(14 "In6.Cu" signal "IN3")
		(16 "In7.Cu" signal "GND3")
		(18 "In8.Cu" signal "VCC")
		(20 "In9.Cu" signal "VCC1")
		(22 "In10.Cu" signal "GND4")
		(24 "In11.Cu" signal "IN4")
		(26 "In12.Cu" signal "GND5")
		(28 "In13.Cu" signal "IN5")
		(30 "In14.Cu" signal "GND6")
		(32 "In15.Cu" signal "IN6")
		(34 "In16.Cu" signal "GND7")
		(2 "B.Cu" signal "BOTTOM")
		(9 "F.Adhes" user "F.Adhesive")
		(11 "B.Adhes" user "B.Adhesive")
		(13 "F.Paste" user "Package Geometry/Pastemask Top")
		(15 "B.Paste" user "Package Geometry/Pastemask Bottom")
		(5 "F.SilkS" user "Ref Des/Silkscreen Top")
		(7 "B.SilkS" user "Ref Des/Silkscreen Bottom")
		(1 "F.Mask" user "Board Geometry/Soldermask Top")
		(3 "B.Mask" user "Board Geometry/Soldermask Bottom")
		(17 "Dwgs.User" user "User.Drawings")
		(19 "Cmts.User" user "User.Comments")
		(21 "Eco1.User" user "User.Eco1")
		(23 "Eco2.User" user "User.Eco2")
		(25 "Edge.Cuts" user "Board Geometry/Outline")
		(27 "Margin" user)
		(31 "F.CrtYd" user "Package Geometry/Place Bound Top")
		(29 "B.CrtYd" user "Package Geometry/Place Bound Bottom")
		(35 "F.Fab" user "Ref Des/Assembly Top")
		(33 "B.Fab" user "Ref Des/Assembly Bottom")
	)
	(footprint ""
		(layer "F.Cu")
		(at 22.86889 -182.595266 180)
		(property "Reference" "PC2222"
			(at 0 0 180)
			(layer "F.SilkS")
			(hide yes)
			(effects
				(font
					(size 1.27 1.27)
				)
			)
		)
		(property "Value" ""
			(at 0 0 180)
			(layer "F.Fab")
			(effects
				(font
					(size 1.27 1.27)
				)
			)
		)
		(duplicate_pad_numbers_are_jumpers no)
		(fp_line
			(start 0.7874 0.4064)
			(end -0.7874 0.4064)
			(stroke
				(width 0.1524)
				(type default)
			)
			(layer "F.SilkS")
		)
		(fp_line
			(start 0.7874 -0.4064)
			(end 0.7874 0.4064)
			(stroke
				(width 0.1524)
				(type default)
			)
			(layer "F.SilkS")
		)
		(fp_line
			(start -0.7874 0.4064)
			(end -0.7874 -0.4064)
			(stroke
				(width 0.1524)
				(type default)
			)
			(layer "F.SilkS")
		)
		(fp_line
			(start -0.7874 -0.4064)
			(end 0.7874 -0.4064)
			(stroke
				(width 0.1524)
				(type default)
			)
			(layer "F.SilkS")
		)
		(fp_line
			(start 0.67945 0.3048)
			(end 0.120396 0.3048)
			(stroke
				(width 0.1)
				(type default)
			)
			(layer "F.Fab")
		)
		(fp_line
			(start 0.67945 -0.3048)
			(end 0.67945 0.3048)
			(stroke
				(width 0.1)
				(type default)
			)
			(layer "F.Fab")
		)
		(fp_line
			(start 0.12065 -0.2794)
			(end 0.12065 -0.3048)
			(stroke
				(width 0.1)
				(type default)
			)
			(layer "F.Fab")
		)
		(fp_line
			(start 0.12065 -0.3048)
			(end 0.67945 -0.3048)
			(stroke
				(width 0.1)
				(type default)
			)
			(layer "F.Fab")
		)
		(fp_line
			(start 0.120396 0.3048)
			(end 0.120396 0.2794)
			(stroke
				(width 0.1)
				(type default)
			)
			(layer "F.Fab")
		)
		(fp_line
			(start 0.120396 0.2794)
			(end -0.12065 0.2794)
			(stroke
				(width 0.1)
				(type default)
			)
			(layer "F.Fab")
		)
		(fp_line
			(start -0.12065 0.3048)
			(end -0.67945 0.3048)
			(stroke
				(width 0.1)
				(type default)
			)
			(layer "F.Fab")
		)
		(fp_line
			(start -0.12065 0.2794)
			(end -0.12065 0.3048)
			(stroke
				(width 0.1)
				(type default)
			)
			(layer "F.Fab")
		)
		(fp_line
			(start -0.12065 -0.2794)
			(end 0.12065 -0.2794)
			(stroke
				(width 0.1)
				(type default)
			)
			(layer "F.Fab")
		)
		(fp_line
			(start -0.12065 -0.305054)
			(end -0.12065 -0.2794)
			(stroke
				(width 0.1)
				(type default)
			)
			(layer "F.Fab")
		)
		(fp_line
			(start -0.67945 0.3048)
			(end -0.67945 -0.305054)
			(stroke
				(width 0.1)
				(type default)
			)
			(layer "F.Fab")
		)
		(fp_line
			(start -0.67945 -0.305054)
			(end -0.12065 -0.305054)
			(stroke
				(width 0.1)
				(type default)
			)
			(layer "F.Fab")
		)
		(pad "1" smd circle
			(at -0.40005 0 180)
			(size 0 0)
			(layers "F.Cu" "F.Mask" "F.Paste")
			(net "PVNN_MAIN_CPU1_VCC")
		)
		(pad "2" smd circle
			(at 0.40005 0 180)
			(size 0 0)
			(layers "F.Cu" "F.Mask" "F.Paste")
			(net "GND")
		)
	)
	(footprint ""
		(layer "F.Cu")
		(at 107.2896 -251.375672 90)
		(property "Reference" "C291"
			(at 0 0 90)
			(layer "F.SilkS")
			(hide yes)
			(effects
				(font
					(size 1.27 1.27)
				)
			)
		)
		(property "Value" ""
			(at 0 0 90)
			(layer "F.Fab")
			(effects
				(font
					(size 1.27 1.27)
				)
			)
		)
		(duplicate_pad_numbers_are_jumpers no)
		(fp_line
			(start 0.7874 -0.4064)
			(end 0.7874 0.4064)
			(stroke
				(width 0.1524)
				(type default)
			)
			(layer "F.SilkS")
		)
		(fp_line
			(start -0.7874 -0.4064)
			(end 0.7874 -0.4064)
			(stroke
				(width 0.1524)
				(type default)
			)
			(layer "F.SilkS")
		)
		(fp_line
			(start 0.7874 0.4064)
			(end -0.7874 0.4064)
			(stroke
				(width 0.1524)
				(type default)
			)
			(layer "F.SilkS")
		)
		(fp_line
			(start -0.7874 0.4064)
			(end -0.7874 -0.4064)
			(stroke
				(width 0.1524)
				(type default)
			)
			(layer "F.SilkS")
		)
		(fp_line
			(start -0.12065 -0.305054)
			(end -0.12065 -0.2794)
			(stroke
				(width 0.1)
				(type default)
			)
			(layer "F.Fab")
		)
		(fp_line
			(start -0.67945 -0.305054)
			(end -0.12065 -0.305054)
			(stroke
				(width 0.1)
				(type default)
			)
			(layer "F.Fab")
		)
		(fp_line
			(start 0.67945 -0.3048)
			(end 0.67945 0.3048)
			(stroke
				(width 0.1)
				(type default)
			)
			(layer "F.Fab")
		)
		(fp_line
			(start 0.12065 -0.3048)
			(end 0.67945 -0.3048)
			(stroke
				(width 0.1)
				(type default)
			)
			(layer "F.Fab")
		)
		(fp_line
			(start 0.12065 -0.2794)
			(end 0.12065 -0.3048)
			(stroke
				(width 0.1)
				(type default)
			)
			(layer "F.Fab")
		)
		(fp_line
			(start -0.12065 -0.2794)
			(end 0.12065 -0.2794)
			(stroke
				(width 0.1)
				(type default)
			)
			(layer "F.Fab")
		)
		(fp_line
			(start 0.120396 0.2794)
			(end -0.12065 0.2794)
			(stroke
				(width 0.1)
				(type default)
			)
			(layer "F.Fab")
		)
		(fp_line
			(start -0.12065 0.2794)
			(end -0.12065 0.3048)
			(stroke
				(width 0.1)
				(type default)
			)
			(layer "F.Fab")
		)
		(fp_line
			(start 0.67945 0.3048)
			(end 0.120396 0.3048)
			(stroke
				(width 0.1)
				(type default)
			)
			(layer "F.Fab")
		)
		(fp_line
			(start 0.120396 0.3048)
			(end 0.120396 0.2794)
			(stroke
				(width 0.1)
				(type default)
			)
			(layer "F.Fab")
		)
		(fp_line
			(start -0.12065 0.3048)
			(end -0.67945 0.3048)
			(stroke
				(width 0.1)
				(type default)
			)
			(layer "F.Fab")
		)
		(fp_line
			(start -0.67945 0.3048)
			(end -0.67945 -0.305054)
			(stroke
				(width 0.1)
				(type default)
			)
			(layer "F.Fab")
		)
		(pad "1" smd circle
			(at -0.40005 0 90)
			(size 0 0)
			(layers "F.Cu" "F.Mask" "F.Paste")
			(net "PVCCIN_CPU1")
		)
		(pad "2" smd circle
			(at 0.40005 0 90)
			(size 0 0)
			(layers "F.Cu" "F.Mask" "F.Paste")
			(net "GND")
		)
	)
	(footprint ""
		(layer "F.Cu")
		(at 82.706718 -19.142202 -90)
		(property "Reference" "R3825"
			(at 0 0 270)
			(layer "F.SilkS")
			(hide yes)
			(effects
				(font
					(size 1.27 1.27)
				)
			)
		)
		(property "Value" ""
			(at 0 0 270)
			(layer "F.Fab")
			(effects
				(font
					(size 1.27 1.27)
				)
			)
		)
		(duplicate_pad_numbers_are_jumpers no)
		(fp_line
			(start -0.7874 0.4064)
			(end -0.7874 -0.4064)
			(stroke
				(width 0.1524)
				(type default)
			)
			(layer "F.SilkS")
		)
		(fp_line
			(start 0.7874 0.4064)
			(end -0.7874 0.4064)
			(stroke
				(width 0.1524)
				(type default)
			)
			(layer "F.SilkS")
		)
		(fp_line
			(start -0.7874 -0.4064)
			(end 0.7874 -0.4064)
			(stroke
				(width 0.1524)
				(type default)
			)
			(layer "F.SilkS")
		)
		(fp_line
			(start 0.7874 -0.4064)
			(end 0.7874 0.4064)
			(stroke
				(width 0.1524)
				(type default)
			)
			(layer "F.SilkS")
		)
		(fp_line
			(start -0.67945 0.3048)
			(end -0.67945 -0.305054)
			(stroke
				(width 0.1)
				(type default)
			)
			(layer "F.Fab")
		)
		(fp_line
			(start -0.12065 0.3048)
			(end -0.67945 0.3048)
			(stroke
				(width 0.1)
				(type default)
			)
			(layer "F.Fab")
		)
		(fp_line
			(start 0.120396 0.3048)
			(end 0.120396 0.2794)
			(stroke
				(width 0.1)
				(type default)
			)
			(layer "F.Fab")
		)
		(fp_line
			(start 0.67945 0.3048)
			(end 0.120396 0.3048)
			(stroke
				(width 0.1)
				(type default)
			)
			(layer "F.Fab")
		)
		(fp_line
			(start -0.12065 0.2794)
			(end -0.12065 0.3048)
			(stroke
				(width 0.1)
				(type default)
			)
			(layer "F.Fab")
		)
		(fp_line
			(start 0.120396 0.2794)
			(end -0.12065 0.2794)
			(stroke
				(width 0.1)
				(type default)
			)
			(layer "F.Fab")
		)
		(fp_line
			(start -0.12065 -0.2794)
			(end 0.12065 -0.2794)
			(stroke
				(width 0.1)
				(type default)
			)
			(layer "F.Fab")
		)
		(fp_line
			(start 0.12065 -0.2794)
			(end 0.12065 -0.3048)
			(stroke
				(width 0.1)
				(type default)
			)
			(layer "F.Fab")
		)
		(fp_line
			(start 0.12065 -0.3048)
			(end 0.67945 -0.3048)
			(stroke
				(width 0.1)
				(type default)
			)
			(layer "F.Fab")
		)
		(fp_line
			(start 0.67945 -0.3048)
			(end 0.67945 0.3048)
			(stroke
				(width 0.1)
				(type default)
			)
			(layer "F.Fab")
		)
		(fp_line
			(start -0.67945 -0.305054)
			(end -0.12065 -0.305054)
			(stroke
				(width 0.1)
				(type default)
			)
			(layer "F.Fab")
		)
		(fp_line
			(start -0.12065 -0.305054)
			(end -0.12065 -0.2794)
			(stroke
				(width 0.1)
				(type default)
			)
			(layer "F.Fab")
		)
		(pad "1" smd circle
			(at -0.40005 0 270)
			(size 0 0)
			(layers "F.Cu" "F.Mask" "F.Paste")
			(net "P3V3_AUX")
		)
		(pad "2" smd circle
			(at 0.40005 0 270)
			(size 0 0)
			(layers "F.Cu" "F.Mask" "F.Paste")
			(net "HP_LVC3_OCP_V3_2_P12V_PWRGD")
		)
	)
	(footprint ""
		(layer "F.Cu")
		(at 118.44528 -405.823166 -90)
		(property "Reference" "R2831"
			(at 0 0 270)
			(layer "F.SilkS")
			(hide yes)
			(effects
				(font
					(size 1.27 1.27)
				)
			)
		)
		(property "Value" ""
			(at 0 0 270)
			(layer "F.Fab")
			(effects
				(font
					(size 1.27 1.27)
				)
			)
		)
		(duplicate_pad_numbers_are_jumpers no)
		(fp_line
			(start -0.7874 0.4064)
			(end -0.7874 -0.4064)
			(stroke
				(width 0.1524)
				(type default)
			)
			(layer "F.SilkS")
		)
		(fp_line
			(start 0.7874 0.4064)
			(end -0.7874 0.4064)
			(stroke
				(width 0.1524)
				(type default)
			)
			(layer "F.SilkS")
		)
		(fp_line
			(start -0.7874 -0.4064)
			(end 0.7874 -0.4064)
			(stroke
				(width 0.1524)
				(type default)
			)
			(layer "F.SilkS")
		)
		(fp_line
			(start 0.7874 -0.4064)
			(end 0.7874 0.4064)
			(stroke
				(width 0.1524)
				(type default)
			)
			(layer "F.SilkS")
		)
		(fp_line
			(start -0.67945 0.3048)
			(end -0.67945 -0.305054)
			(stroke
				(width 0.1)
				(type default)
			)
			(layer "F.Fab")
		)
		(fp_line
			(start -0.12065 0.3048)
			(end -0.67945 0.3048)
			(stroke
				(width 0.1)
				(type default)
			)
			(layer "F.Fab")
		)
		(fp_line
			(start 0.120396 0.3048)
			(end 0.120396 0.2794)
			(stroke
				(width 0.1)
				(type default)
			)
			(layer "F.Fab")
		)
		(fp_line
			(start 0.67945 0.3048)
			(end 0.120396 0.3048)
			(stroke
				(width 0.1)
				(type default)
			)
			(layer "F.Fab")
		)
		(fp_line
			(start -0.12065 0.2794)
			(end -0.12065 0.3048)
			(stroke
				(width 0.1)
				(type default)
			)
			(layer "F.Fab")
		)
		(fp_line
			(start 0.120396 0.2794)
			(end -0.12065 0.2794)
			(stroke
				(width 0.1)
				(type default)
			)
			(layer "F.Fab")
		)
		(fp_line
			(start -0.12065 -0.2794)
			(end 0.12065 -0.2794)
			(stroke
				(width 0.1)
				(type default)
			)
			(layer "F.Fab")
		)
		(fp_line
			(start 0.12065 -0.2794)
			(end 0.12065 -0.3048)
			(stroke
				(width 0.1)
				(type default)
			)
			(layer "F.Fab")
		)
		(fp_line
			(start 0.12065 -0.3048)
			(end 0.67945 -0.3048)
			(stroke
				(width 0.1)
				(type default)
			)
			(layer "F.Fab")
		)
		(fp_line
			(start 0.67945 -0.3048)
			(end 0.67945 0.3048)
			(stroke
				(width 0.1)
				(type default)
			)
			(layer "F.Fab")
		)
		(fp_line
			(start -0.67945 -0.305054)
			(end -0.12065 -0.305054)
			(stroke
				(width 0.1)
				(type default)
			)
			(layer "F.Fab")
		)
		(fp_line
			(start -0.12065 -0.305054)
			(end -0.12065 -0.2794)
			(stroke
				(width 0.1)
				(type default)
			)
			(layer "F.Fab")
		)
		(pad "1" smd circle
			(at -0.40005 0 270)
			(size 0 0)
			(layers "F.Cu" "F.Mask" "F.Paste")
			(net "BIC_MONITER")
		)
		(pad "2" smd circle
			(at 0.40005 0 270)
			(size 0 0)
			(layers "F.Cu" "F.Mask" "F.Paste")
			(net "GND")
		)
	)
	(footprint ""
		(layer "F.Cu")
		(at 193.60388 -106.225848)
		(property "Reference" "R1494"
			(at 0 0 0)
			(layer "F.SilkS")
			(hide yes)
			(effects
				(font
					(size 1.27 1.27)
				)
			)
		)
		(property "Value" ""
			(at 0 0 0)
			(layer "F.Fab")
			(effects
				(font
					(size 1.27 1.27)
				)
			)
		)
		(duplicate_pad_numbers_are_jumpers no)
		(fp_line
			(start -0.7874 -0.4064)
			(end 0.7874 -0.4064)
			(stroke
				(width 0.1524)
				(type default)
			)
			(layer "F.SilkS")
		)
		(fp_line
			(start -0.7874 0.4064)
			(end -0.7874 -0.4064)
			(stroke
				(width 0.1524)
				(type default)
			)
			(layer "F.SilkS")
		)
		(fp_line
			(start 0.7874 -0.4064)
			(end 0.7874 0.4064)
			(stroke
				(width 0.1524)
				(type default)
			)
			(layer "F.SilkS")
		)
		(fp_line
			(start 0.7874 0.4064)
			(end -0.7874 0.4064)
			(stroke
				(width 0.1524)
				(type default)
			)
			(layer "F.SilkS")
		)
		(fp_line
			(start -0.67945 -0.305054)
			(end -0.12065 -0.305054)
			(stroke
				(width 0.1)
				(type default)
			)
			(layer "F.Fab")
		)
		(fp_line
			(start -0.67945 0.3048)
			(end -0.67945 -0.305054)
			(stroke
				(width 0.1)
				(type default)
			)
			(layer "F.Fab")
		)
		(fp_line
			(start -0.12065 -0.305054)
			(end -0.12065 -0.2794)
			(stroke
				(width 0.1)
				(type default)
			)
			(layer "F.Fab")
		)
		(fp_line
			(start -0.12065 -0.2794)
			(end 0.12065 -0.2794)
			(stroke
				(width 0.1)
				(type default)
			)
			(layer "F.Fab")
		)
		(fp_line
			(start -0.12065 0.2794)
			(end -0.12065 0.3048)
			(stroke
				(width 0.1)
				(type default)
			)
			(layer "F.Fab")
		)
		(fp_line
			(start -0.12065 0.3048)
			(end -0.67945 0.3048)
			(stroke
				(width 0.1)
				(type default)
			)
			(layer "F.Fab")
		)
		(fp_line
			(start 0.120396 0.2794)
			(end -0.12065 0.2794)
			(stroke
				(width 0.1)
				(type default)
			)
			(layer "F.Fab")
		)
		(fp_line
			(start 0.120396 0.3048)
			(end 0.120396 0.2794)
			(stroke
				(width 0.1)
				(type default)
			)
			(layer "F.Fab")
		)
		(fp_line
			(start 0.12065 -0.3048)
			(end 0.67945 -0.3048)
			(stroke
				(width 0.1)
				(type default)
			)
			(layer "F.Fab")
		)
		(fp_line
			(start 0.12065 -0.2794)
			(end 0.12065 -0.3048)
			(stroke
				(width 0.1)
				(type default)
			)
			(layer "F.Fab")
		)
		(fp_line
			(start 0.67945 -0.3048)
			(end 0.67945 0.3048)
			(stroke
				(width 0.1)
				(type default)
			)
			(layer "F.Fab")
		)
		(fp_line
			(start 0.67945 0.3048)
			(end 0.120396 0.3048)
			(stroke
				(width 0.1)
				(type default)
			)
			(layer "F.Fab")
		)
		(pad "1" smd circle
			(at -0.40005 0)
			(size 0 0)
			(layers "F.Cu" "F.Mask" "F.Paste")
			(net "FM_DIS_PS_PWROK_DLY")
		)
		(pad "2" smd circle
			(at 0.40005 0)
			(size 0 0)
			(layers "F.Cu" "F.Mask" "F.Paste")
			(net "GND")
		)
	)
)
